FILE_TYPE = MULTI_PHYS_TABLE;

PART 'AST2600A3GP'

{========================================================================================}
:VALUE          | PART_TYPE | MATERIAL | PART_NUMBER    = STANDARD        | LIFECYCLE          | PART_NUMBER   | JEDEC_TYPE           | DESCRIPTION                         | MANUFTR | MANUF_PN       | RD_CMPLS_LVL | CMPLS_LVL | FROM_PJ       | CLASS | DIP_SMD | DATA                   | EE_CHECK_LIST | FP_ECN | PSL | CREATOR | STATUS | MSD | ESD_CDM | ESD_HBM | ESD_MM | PIN_LENGTH_SHORT_PIN | PIN_LENGTH_LONG_PIN | CREATEDAY  ;
{========================================================================================}
 'AST2600A3-GP' | 'SMLF'    | 'IC'     | 'AJ026000T06'(!) = ''              | ''                 | 'AJ026000T06' |'BGA624_0-8_21X21XA'| 'IC(624P)AST2600A3-GP(TFBGA)'       | 'APD'   | 'AST2600A3-GP' | 'EP(V1)'     | ''        | 'A5G-JASMINE' | 'IC'  | ''      | 'APD_AST2600A3-GP.pdf' | ''            | ''     | ''  | ''      | ''     | ''  | ''      | ''      | ''     | '0 MILS'             | '0 MILS'            | '20210709'
 'AST2600A3-GP' | 'SMLF'    | 'EMPTY'  | 'AJ026000T06'(!) = ''              | ''                 | 'AJ026000T06' |'BGA624_0-8_21X21XA'| 'IC(624P)AST2600A3-GP(TFBGA)'       | 'APD'   | 'AST2600A3-GP' | 'EP(V1)'     | ''        | 'A5G-JASMINE' | 'IC'  | ''      | 'APD_AST2600A3-GP.pdf' | ''            | ''     | ''  | ''      | ''     | ''  | ''      | ''      | ''     | '0 MILS'             | '0 MILS'            | '20210709'
 'AST2600A3-GP' | 'SMLF'    | 'IC'     | 'AJ026000T07'(!) = ''               | ''               | 'AJ026000T07' |'BGA624_0-8_21X21XA'| 'IC(624P)AST2600A3-GP(TFBGA)AMAASN' | 'APD'   | 'AST2600A3-GP' | 'EP(V1)'     | 'EP(V1)'  | 'A5G-JASMINE' | 'IC'  | ''      | 'APD_AST2600A3-GP.pdf' | ''            | ''     | ''  | ''      | ''     | ''  | ''      | ''      | ''     | '0 MILS'             | '0 MILS'            | '20230428'
 'AST2600A3-GP' | 'SMLF'    | 'EMPTY'  | 'AJ026000T07'(!) = ''               | ''               | 'AJ026000T07' |'BGA624_0-8_21X21XA'| 'IC(624P)AST2600A3-GP(TFBGA)AMAASN' | 'APD'   | 'AST2600A3-GP' | 'EP(V1)'     | 'EP(V1)'  | 'A5G-JASMINE' | 'IC'  | ''      | 'APD_AST2600A3-GP.pdf' | ''            | ''     | ''  | ''      | ''     | ''  | ''      | ''      | ''     | '0 MILS'             | '0 MILS'            | '20230428'

END_PART

END.

